# BASEBOARD_FAB2 (Tioga Pass) — schematic netlist excerpt (pin names and nets, part order shuffled) for the footprints in the layout excerpt that follows; sources: Cadence DE-HDL packaged netlist, KiCad conversion of Wiwynn_Tioga_Pass_MB.brd

C4B12  CAP_A  0.01UF 25V 10% X7R  pkg 0402V  page 49 : A = M_D_VREF ; B = GND
DS9A7  LED  IC  pkg A1LF  page 158 : A = FM_UARTSW_MSB_R_N ; C = FM_UARTSW_MSB_N

(kicad_pcb
	(version 20260206)
	(generator "pcbnew")
	(generator_version "10.0")
	(general
		(thickness 1.6)
		(legacy_teardrops no)
	)
	(paper "A4")
	(title_block
		(title "Wiwynn_Tioga_Pass_MB.brd")
		(comment 1 "Tioga Pass / footprints 401-402 of 4770")
	)
	(layers
		(0 "F.Cu" signal "TOP")
		(4 "In1.Cu" signal "L2GND")
		(6 "In2.Cu" signal "L3")
		(8 "In3.Cu" signal "L4GND")
		(10 "In4.Cu" signal "L5")
		(12 "In5.Cu" signal "L6GND")
		(14 "In6.Cu" signal "L7VCC")
		(16 "In7.Cu" signal "L8VCC")
		(18 "In8.Cu" signal "L9GND")
		(20 "In9.Cu" signal "L10")
		(22 "In10.Cu" signal "L11GND")
		(24 "In11.Cu" signal "L12")
		(26 "In12.Cu" signal "L13GND")
		(2 "B.Cu" signal "BOTTOM")
		(9 "F.Adhes" user "F.Adhesive")
		(11 "B.Adhes" user "B.Adhesive")
		(13 "F.Paste" user "Package Geometry/Pastemask Top")
		(15 "B.Paste" user "Package Geometry/Pastemask Bottom")
		(5 "F.SilkS" user "Ref Des/Silkscreen Top")
		(7 "B.SilkS" user "Ref Des/Silkscreen Bottom")
		(1 "F.Mask" user "Board Geometry/Soldermask Top")
		(3 "B.Mask" user "Board Geometry/Soldermask Bottom")
		(17 "Dwgs.User" user "User.Drawings")
		(19 "Cmts.User" user "User.Comments")
		(21 "Eco1.User" user "User.Eco1")
		(23 "Eco2.User" user "User.Eco2")
		(25 "Edge.Cuts" user "Board Geometry/Outline")
		(27 "Margin" user)
		(31 "F.CrtYd" user "Package Geometry/Place Bound Top")
		(29 "B.CrtYd" user "Package Geometry/Place Bound Bottom")
		(35 "F.Fab" user "Ref Des/Assembly Top")
		(33 "B.Fab" user "Ref Des/Assembly Bottom")
	)
	(footprint ""
		(layer "F.Cu")
		(at 498.620034 -137.278618 90)
		(property "Reference" "DS9A7"
			(at -0.76073 0.85344 0)
			(unlocked yes)
			(layer "F.SilkS")
			(effects
				(font
					(size 0.7874 0.5842)
					(thickness 0.1524)
				)
			)
		)
		(property "Value" ""
			(at 0 0 90)
			(layer "F.Fab")
			(effects
				(font
					(size 1.27 1.27)
				)
			)
		)
		(duplicate_pad_numbers_are_jumpers no)
		(fp_line
			(start -1.353312 -0.498094)
			(end -1.353312 0.413512)
			(stroke
				(width 0.1524)
				(type default)
			)
			(layer "F.SilkS")
		)
		(fp_line
			(start -0.87249 0.413512)
			(end -1.353312 1.246378)
			(stroke
				(width 0.1524)
				(type default)
			)
			(layer "F.SilkS")
		)
		(fp_line
			(start -1.353312 0.413512)
			(end -0.87249 0.413512)
			(stroke
				(width 0.1524)
				(type default)
			)
			(layer "F.SilkS")
		)
		(fp_line
			(start -1.834134 0.413512)
			(end -1.353312 0.413512)
			(stroke
				(width 0.1524)
				(type default)
			)
			(layer "F.SilkS")
		)
		(fp_line
			(start -1.353312 1.246378)
			(end -1.834134 0.413512)
			(stroke
				(width 0.1524)
				(type default)
			)
			(layer "F.SilkS")
		)
		(fp_line
			(start -1.834134 1.246378)
			(end -0.87249 1.246378)
			(stroke
				(width 0.1524)
				(type default)
			)
			(layer "F.SilkS")
		)
		(fp_line
			(start -1.353312 2.36982)
			(end -1.353312 1.246378)
			(stroke
				(width 0.1524)
				(type default)
			)
			(layer "F.SilkS")
		)
		(fp_rect
			(start -0.4064 1.6891)
			(end 0.4064 0.0889)
			(stroke
				(width 0)
				(type default)
			)
			(fill no)
			(layer "F.CrtYd")
		)
		(fp_line
			(start 0.4064 0.0889)
			(end 0.4064 1.6891)
			(stroke
				(width 0.1)
				(type default)
			)
			(layer "F.Fab")
		)
		(fp_line
			(start -0.4064 0.0889)
			(end 0.4064 0.0889)
			(stroke
				(width 0.1)
				(type default)
			)
			(layer "F.Fab")
		)
		(fp_line
			(start -0.87249 0.413512)
			(end -1.353312 1.246378)
			(stroke
				(width 0.1)
				(type default)
			)
			(layer "F.Fab")
		)
		(fp_line
			(start -1.353312 0.413512)
			(end -1.353312 -0.498094)
			(stroke
				(width 0.1)
				(type default)
			)
			(layer "F.Fab")
		)
		(fp_line
			(start -1.834134 0.413512)
			(end -0.87249 0.413512)
			(stroke
				(width 0.1)
				(type default)
			)
			(layer "F.Fab")
		)
		(fp_line
			(start -1.353312 1.246378)
			(end -1.834134 0.413512)
			(stroke
				(width 0.1)
				(type default)
			)
			(layer "F.Fab")
		)
		(fp_line
			(start -1.353312 1.246378)
			(end -1.353312 2.36982)
			(stroke
				(width 0.1)
				(type default)
			)
			(layer "F.Fab")
		)
		(fp_line
			(start -1.834134 1.246378)
			(end -0.87249 1.246378)
			(stroke
				(width 0.1)
				(type default)
			)
			(layer "F.Fab")
		)
		(fp_line
			(start 0.4064 1.6891)
			(end -0.4064 1.6891)
			(stroke
				(width 0.1)
				(type default)
			)
			(layer "F.Fab")
		)
		(fp_line
			(start -0.4064 1.6891)
			(end -0.4064 0.0889)
			(stroke
				(width 0.1)
				(type default)
			)
			(layer "F.Fab")
		)
		(pad "1" smd rect
			(at 0 0 90)
			(size 0.762 1.27)
			(layers "F.Cu" "F.Mask" "F.Paste")
			(net "FM_UARTSW_MSB_R_N")
		)
		(pad "2" smd rect
			(at 0 1.778 90)
			(size 0.762 1.27)
			(layers "F.Cu" "F.Mask" "F.Paste")
			(net "FM_UARTSW_MSB_N")
		)
		(zone
			(layer "F.Cu")
			(hatch none 0.5)
			(connect_pads
				(clearance 0)
			)
			(min_thickness 0.25)
			(keepout
				(tracks not_allowed)
				(vias allowed)
				(pads allowed)
				(copperpour not_allowed)
				(footprints allowed)
			)
			(placement
				(enabled no)
				(sheetname "")
			)
			(fill
				(thermal_gap 0.5)
				(thermal_bridge_width 0.5)
				(island_removal_mode 0)
			)
			(polygon
				(pts
					(xy 499.280434 -136.897618) (xy 499.280434 -137.659618) (xy 499.737634 -137.659618) (xy 499.737634 -136.897618)
				)
			)
		)
		(zone
			(layer "F.Cu")
			(hatch none 0.5)
			(connect_pads
				(clearance 0)
			)
			(min_thickness 0.25)
			(keepout
				(tracks allowed)
				(vias not_allowed)
				(pads allowed)
				(copperpour not_allowed)
				(footprints allowed)
			)
			(placement
				(enabled no)
				(sheetname "")
			)
			(fill
				(thermal_gap 0.5)
				(thermal_bridge_width 0.5)
				(island_removal_mode 0)
			)
			(polygon
				(pts
					(xy 499.737634 -136.897618) (xy 499.737634 -137.659618) (xy 499.280434 -137.659618) (xy 499.280434 -136.897618)
				)
			)
		)
	)
	(footprint ""
		(layer "F.Cu")
		(at 195.5546 -130.2512 90)
		(property "Reference" "C4B12"
			(at 0 0 90)
			(layer "F.SilkS")
			(hide yes)
			(effects
				(font
					(size 1.27 1.27)
				)
			)
		)
		(property "Value" ""
			(at 0 0 90)
			(layer "F.Fab")
			(effects
				(font
					(size 1.27 1.27)
				)
			)
		)
		(duplicate_pad_numbers_are_jumpers no)
		(fp_poly
			(pts
				(xy 0.3048 -0.1016) (xy 0.3048 0.9906) (xy -0.3048 0.9906) (xy -0.3048 -0.1016)
			)
			(stroke
				(width 0)
				(type default)
			)
			(fill no)
			(layer "F.CrtYd")
		)
		(fp_line
			(start 0.3048 -0.1016)
			(end -0.3048 -0.1016)
			(stroke
				(width 0.1)
				(type default)
			)
			(layer "F.Fab")
		)
		(fp_line
			(start -0.3048 -0.1016)
			(end -0.3048 0.9906)
			(stroke
				(width 0.1)
				(type default)
			)
			(layer "F.Fab")
		)
		(fp_line
			(start 0.3048 0.9906)
			(end 0.3048 -0.1016)
			(stroke
				(width 0.1)
				(type default)
			)
			(layer "F.Fab")
		)
		(fp_line
			(start -0.3048 0.9906)
			(end 0.3048 0.9906)
			(stroke
				(width 0.1)
				(type default)
			)
			(layer "F.Fab")
		)
		(pad "1" smd rect
			(at 0 0 90)
			(size 0.508 0.508)
			(layers "F.Cu" "F.Mask" "F.Paste")
			(net "M_D_VREF")
		)
		(pad "2" smd rect
			(at 0 0.889 90)
			(size 0.508 0.508)
			(layers "F.Cu" "F.Mask" "F.Paste")
			(net "GND")
		)
		(zone
			(layer "F.Cu")
			(hatch none 0.5)
			(connect_pads
				(clearance 0)
			)
			(min_thickness 0.25)
			(keepout
				(tracks allowed)
				(vias not_allowed)
				(pads allowed)
				(copperpour not_allowed)
				(footprints allowed)
			)
			(placement
				(enabled no)
				(sheetname "")
			)
			(fill
				(thermal_gap 0.5)
				(thermal_bridge_width 0.5)
				(island_removal_mode 0)
			)
			(polygon
				(pts
					(xy 195.8086 -129.9972) (xy 195.8086 -130.5052) (xy 196.1896 -130.5052) (xy 196.1896 -129.9972)
				)
			)
		)
		(zone
			(layer "F.Cu")
			(hatch none 0.5)
			(connect_pads
				(clearance 0)
			)
			(min_thickness 0.25)
			(keepout
				(tracks not_allowed)
				(vias allowed)
				(pads allowed)
				(copperpour not_allowed)
				(footprints allowed)
			)
			(placement
				(enabled no)
				(sheetname "")
			)
			(fill
				(thermal_gap 0.5)
				(thermal_bridge_width 0.5)
				(island_removal_mode 0)
			)
			(polygon
				(pts
					(xy 196.1896 -129.9972) (xy 196.1896 -130.5052) (xy 195.8086 -130.5052) (xy 195.8086 -129.9972)
				)
			)
		)
	)
)
